# T6G (Grand Teton) — schematic netlist excerpt (pin names and nets, part order shuffled) for the footprints in the layout excerpt that follows; sources: Cadence DE-HDL packaged netlist, KiCad conversion of 04192023_DAF0TMB3IC0_F0TG_MB_C_brd_V02_OCP.brd

C386  Q_CAP  1UF 4V 20% X6S  pkg 0201  page 345 : A = P0V9_CPU1_RT2_2A ; B = GND
C6009  Q_CAP  1UF 25V 10% X6S  pkg C0402  page 112 : A = P3V3_AUX ; B = GND
R6040  Q_RES  10K 5% CHIP  pkg 0402LF  page 167 : A = P1V8_AUX ; B = PU_FPGA_DEBUG_LED_CTRL

(kicad_pcb
	(version 20260206)
	(generator "pcbnew")
	(generator_version "10.0")
	(general
		(thickness 1.6)
		(legacy_teardrops no)
	)
	(paper "A4")
	(title_block
		(title "04192023_DAF0TMB3IC0_F0TG_MB_C_brd_V02_OCP.brd")
		(comment 1 "Grand Teton / footprints 7698-7700 of 8354")
	)
	(layers
		(0 "F.Cu" signal "TOP")
		(4 "In1.Cu" signal "GND")
		(6 "In2.Cu" signal "IN1")
		(8 "In3.Cu" signal "GND1")
		(10 "In4.Cu" signal "IN2")
		(12 "In5.Cu" signal "GND2")
		(14 "In6.Cu" signal "IN3")
		(16 "In7.Cu" signal "GND3")
		(18 "In8.Cu" signal "VCC")
		(20 "In9.Cu" signal "VCC1")
		(22 "In10.Cu" signal "GND4")
		(24 "In11.Cu" signal "IN4")
		(26 "In12.Cu" signal "GND5")
		(28 "In13.Cu" signal "IN5")
		(30 "In14.Cu" signal "GND6")
		(32 "In15.Cu" signal "IN6")
		(34 "In16.Cu" signal "GND7")
		(2 "B.Cu" signal "BOTTOM")
		(9 "F.Adhes" user "F.Adhesive")
		(11 "B.Adhes" user "B.Adhesive")
		(13 "F.Paste" user "Package Geometry/Pastemask Top")
		(15 "B.Paste" user "Package Geometry/Pastemask Bottom")
		(5 "F.SilkS" user "Ref Des/Silkscreen Top")
		(7 "B.SilkS" user "Ref Des/Silkscreen Bottom")
		(1 "F.Mask" user "Board Geometry/Soldermask Top")
		(3 "B.Mask" user "Board Geometry/Soldermask Bottom")
		(17 "Dwgs.User" user "User.Drawings")
		(19 "Cmts.User" user "User.Comments")
		(21 "Eco1.User" user "User.Eco1")
		(23 "Eco2.User" user "User.Eco2")
		(25 "Edge.Cuts" user "Board Geometry/Outline")
		(27 "Margin" user)
		(31 "F.CrtYd" user "Package Geometry/Place Bound Top")
		(29 "B.CrtYd" user "Package Geometry/Place Bound Bottom")
		(35 "F.Fab" user "Ref Des/Assembly Top")
		(33 "B.Fab" user "Ref Des/Assembly Bottom")
	)
	(footprint ""
		(layer "B.Cu")
		(at 15.094458 -420.214298)
		(property "Reference" "C6009"
			(at 0 0 0)
			(layer "B.SilkS")
			(hide yes)
			(effects
				(font
					(size 1.27 1.27)
				)
				(justify mirror)
			)
		)
		(property "Value" ""
			(at 0 0 0)
			(layer "B.Fab")
			(effects
				(font
					(size 1.27 1.27)
				)
				(justify mirror)
			)
		)
		(duplicate_pad_numbers_are_jumpers no)
		(fp_line
			(start -0.7874 -0.4064)
			(end -0.7874 0.4064)
			(stroke
				(width 0.1524)
				(type default)
			)
			(layer "B.SilkS")
		)
		(fp_line
			(start -0.7874 0.4064)
			(end 0.7874 0.4064)
			(stroke
				(width 0.1524)
				(type default)
			)
			(layer "B.SilkS")
		)
		(fp_line
			(start 0.7874 -0.4064)
			(end -0.7874 -0.4064)
			(stroke
				(width 0.1524)
				(type default)
			)
			(layer "B.SilkS")
		)
		(fp_line
			(start 0.7874 0.4064)
			(end 0.7874 -0.4064)
			(stroke
				(width 0.1524)
				(type default)
			)
			(layer "B.SilkS")
		)
		(fp_line
			(start -0.67945 -0.3048)
			(end -0.67945 0.3048)
			(stroke
				(width 0.1)
				(type default)
			)
			(layer "B.Fab")
		)
		(fp_line
			(start -0.67945 0.3048)
			(end -0.120396 0.3048)
			(stroke
				(width 0.1)
				(type default)
			)
			(layer "B.Fab")
		)
		(fp_line
			(start -0.12065 -0.3048)
			(end -0.67945 -0.3048)
			(stroke
				(width 0.1)
				(type default)
			)
			(layer "B.Fab")
		)
		(fp_line
			(start -0.12065 -0.2794)
			(end -0.12065 -0.3048)
			(stroke
				(width 0.1)
				(type default)
			)
			(layer "B.Fab")
		)
		(fp_line
			(start -0.120396 0.2794)
			(end 0.12065 0.2794)
			(stroke
				(width 0.1)
				(type default)
			)
			(layer "B.Fab")
		)
		(fp_line
			(start -0.120396 0.3048)
			(end -0.120396 0.2794)
			(stroke
				(width 0.1)
				(type default)
			)
			(layer "B.Fab")
		)
		(fp_line
			(start 0.12065 -0.305054)
			(end 0.12065 -0.2794)
			(stroke
				(width 0.1)
				(type default)
			)
			(layer "B.Fab")
		)
		(fp_line
			(start 0.12065 -0.2794)
			(end -0.12065 -0.2794)
			(stroke
				(width 0.1)
				(type default)
			)
			(layer "B.Fab")
		)
		(fp_line
			(start 0.12065 0.2794)
			(end 0.12065 0.3048)
			(stroke
				(width 0.1)
				(type default)
			)
			(layer "B.Fab")
		)
		(fp_line
			(start 0.12065 0.3048)
			(end 0.67945 0.3048)
			(stroke
				(width 0.1)
				(type default)
			)
			(layer "B.Fab")
		)
		(fp_line
			(start 0.67945 -0.305054)
			(end 0.12065 -0.305054)
			(stroke
				(width 0.1)
				(type default)
			)
			(layer "B.Fab")
		)
		(fp_line
			(start 0.67945 0.3048)
			(end 0.67945 -0.305054)
			(stroke
				(width 0.1)
				(type default)
			)
			(layer "B.Fab")
		)
		(pad "1" smd circle
			(at 0.40005 0 180)
			(size 0 0)
			(layers "B.Cu" "B.Mask" "B.Paste")
			(net "P3V3_AUX")
		)
		(pad "2" smd circle
			(at -0.40005 0 180)
			(size 0 0)
			(layers "B.Cu" "B.Mask" "B.Paste")
			(net "GND")
		)
	)
	(footprint ""
		(layer "B.Cu")
		(at 146.80057 -385.50088 -90)
		(property "Reference" "C386"
			(at 0 0 90)
			(layer "B.SilkS")
			(hide yes)
			(effects
				(font
					(size 1.27 1.27)
				)
				(justify mirror)
			)
		)
		(property "Value" ""
			(at 0 0 90)
			(layer "B.Fab")
			(effects
				(font
					(size 1.27 1.27)
				)
				(justify mirror)
			)
		)
		(duplicate_pad_numbers_are_jumpers no)
		(fp_line
			(start -0.299974 0.150114)
			(end 0.299974 0.150114)
			(stroke
				(width 0.1)
				(type default)
			)
			(layer "B.Fab")
		)
		(fp_line
			(start 0.299974 0.150114)
			(end 0.299974 -0.150114)
			(stroke
				(width 0.1)
				(type default)
			)
			(layer "B.Fab")
		)
		(fp_line
			(start -0.299974 -0.150114)
			(end -0.299974 0.150114)
			(stroke
				(width 0.1)
				(type default)
			)
			(layer "B.Fab")
		)
		(fp_line
			(start 0.299974 -0.150114)
			(end -0.299974 -0.150114)
			(stroke
				(width 0.1)
				(type default)
			)
			(layer "B.Fab")
		)
		(pad "1" smd rect
			(at 0.2667 0 90)
			(size 0.3048 0.381)
			(layers "B.Cu" "B.Mask" "B.Paste")
			(net "P0V9_CPU1_RT2_2A")
		)
		(pad "2" smd rect
			(at -0.2667 0 90)
			(size 0.3048 0.381)
			(layers "B.Cu" "B.Mask" "B.Paste")
			(net "GND")
		)
	)
	(footprint ""
		(layer "B.Cu")
		(at 426.53585 -30.927548)
		(property "Reference" "R6040"
			(at 0 0 0)
			(layer "B.SilkS")
			(hide yes)
			(effects
				(font
					(size 1.27 1.27)
				)
				(justify mirror)
			)
		)
		(property "Value" ""
			(at 0 0 0)
			(layer "B.Fab")
			(effects
				(font
					(size 1.27 1.27)
				)
				(justify mirror)
			)
		)
		(duplicate_pad_numbers_are_jumpers no)
		(fp_line
			(start -0.7874 -0.4064)
			(end -0.7874 0.4064)
			(stroke
				(width 0.1524)
				(type default)
			)
			(layer "B.SilkS")
		)
		(fp_line
			(start -0.7874 0.4064)
			(end 0.7874 0.4064)
			(stroke
				(width 0.1524)
				(type default)
			)
			(layer "B.SilkS")
		)
		(fp_line
			(start 0.7874 -0.4064)
			(end -0.7874 -0.4064)
			(stroke
				(width 0.1524)
				(type default)
			)
			(layer "B.SilkS")
		)
		(fp_line
			(start 0.7874 0.4064)
			(end 0.7874 -0.4064)
			(stroke
				(width 0.1524)
				(type default)
			)
			(layer "B.SilkS")
		)
		(fp_line
			(start -0.67945 -0.3048)
			(end -0.67945 0.3048)
			(stroke
				(width 0.1)
				(type default)
			)
			(layer "B.Fab")
		)
		(fp_line
			(start -0.67945 0.3048)
			(end -0.120396 0.3048)
			(stroke
				(width 0.1)
				(type default)
			)
			(layer "B.Fab")
		)
		(fp_line
			(start -0.12065 -0.3048)
			(end -0.67945 -0.3048)
			(stroke
				(width 0.1)
				(type default)
			)
			(layer "B.Fab")
		)
		(fp_line
			(start -0.12065 -0.2794)
			(end -0.12065 -0.3048)
			(stroke
				(width 0.1)
				(type default)
			)
			(layer "B.Fab")
		)
		(fp_line
			(start -0.120396 0.2794)
			(end 0.12065 0.2794)
			(stroke
				(width 0.1)
				(type default)
			)
			(layer "B.Fab")
		)
		(fp_line
			(start -0.120396 0.3048)
			(end -0.120396 0.2794)
			(stroke
				(width 0.1)
				(type default)
			)
			(layer "B.Fab")
		)
		(fp_line
			(start 0.12065 -0.305054)
			(end 0.12065 -0.2794)
			(stroke
				(width 0.1)
				(type default)
			)
			(layer "B.Fab")
		)
		(fp_line
			(start 0.12065 -0.2794)
			(end -0.12065 -0.2794)
			(stroke
				(width 0.1)
				(type default)
			)
			(layer "B.Fab")
		)
		(fp_line
			(start 0.12065 0.2794)
			(end 0.12065 0.3048)
			(stroke
				(width 0.1)
				(type default)
			)
			(layer "B.Fab")
		)
		(fp_line
			(start 0.12065 0.3048)
			(end 0.67945 0.3048)
			(stroke
				(width 0.1)
				(type default)
			)
			(layer "B.Fab")
		)
		(fp_line
			(start 0.67945 -0.305054)
			(end 0.12065 -0.305054)
			(stroke
				(width 0.1)
				(type default)
			)
			(layer "B.Fab")
		)
		(fp_line
			(start 0.67945 0.3048)
			(end 0.67945 -0.305054)
			(stroke
				(width 0.1)
				(type default)
			)
			(layer "B.Fab")
		)
		(pad "1" smd circle
			(at 0.40005 0 180)
			(size 0 0)
			(layers "B.Cu" "B.Mask" "B.Paste")
			(net "P1V8_AUX")
		)
		(pad "2" smd circle
			(at -0.40005 0 180)
			(size 0 0)
			(layers "B.Cu" "B.Mask" "B.Paste")
			(net "PU_FPGA_DEBUG_LED_CTRL")
		)
	)
)
